(kicad_pcb
	(version 20260206)
	(generator "pcbnew")
	(generator_version "10.0")
	(general
		(thickness 1.6)
		(legacy_teardrops no)
	)
	(paper "A4")
	(title_block
		(title "01162023_DA0F0TEBIF0_F0T_Expander_BD_F_brd_V02_OCP.brd")
		(comment 1 "Grand Teton / footprints 2270-2273 of 9728")
	)
	(layers
		(0 "F.Cu" signal "TOP")
		(4 "In1.Cu" signal "GND")
		(6 "In2.Cu" signal "VCC")
		(8 "In3.Cu" signal "VCC1")
		(10 "In4.Cu" signal "GND1")
		(12 "In5.Cu" signal "IN1")
		(14 "In6.Cu" signal "GND2")
		(16 "In7.Cu" signal "IN2")
		(18 "In8.Cu" signal "GND3")
		(20 "In9.Cu" signal "IN3")
		(22 "In10.Cu" signal "GND4")
		(24 "In11.Cu" signal "IN4")
		(26 "In12.Cu" signal "GND5")
		(28 "In13.Cu" signal "IN5")
		(30 "In14.Cu" signal "GND6")
		(32 "In15.Cu" signal "IN6")
		(34 "In16.Cu" signal "GND7")
		(2 "B.Cu" signal "BOTTOM")
		(9 "F.Adhes" user "F.Adhesive")
		(11 "B.Adhes" user "B.Adhesive")
		(13 "F.Paste" user "Package Geometry/Pastemask Top")
		(15 "B.Paste" user "Package Geometry/Pastemask Bottom")
		(5 "F.SilkS" user "Ref Des/Silkscreen Top")
		(7 "B.SilkS" user "Ref Des/Silkscreen Bottom")
		(1 "F.Mask" user "Board Geometry/Soldermask Top")
		(3 "B.Mask" user "Board Geometry/Soldermask Bottom")
		(17 "Dwgs.User" user "User.Drawings")
		(19 "Cmts.User" user "User.Comments")
		(21 "Eco1.User" user "User.Eco1")
		(23 "Eco2.User" user "User.Eco2")
		(25 "Edge.Cuts" user "Board Geometry/Outline")
		(27 "Margin" user)
		(31 "F.CrtYd" user "Package Geometry/Place Bound Top")
		(29 "B.CrtYd" user "Package Geometry/Place Bound Bottom")
		(35 "F.Fab" user "Ref Des/Assembly Top")
		(33 "B.Fab" user "Ref Des/Assembly Bottom")
	)
	(footprint ""
		(layer "F.Cu")
		(at 359.148126 -183.107076 180)
		(property "Reference" "R4680"
			(at 0 0 180)
			(layer "F.SilkS")
			(hide yes)
			(effects
				(font
					(size 1.27 1.27)
				)
			)
		)
		(property "Value" ""
			(at 0 0 180)
			(layer "F.Fab")
			(effects
				(font
					(size 1.27 1.27)
				)
			)
		)
		(duplicate_pad_numbers_are_jumpers no)
		(fp_line
			(start 0.7874 0.4064)
			(end -0.7874 0.4064)
			(stroke
				(width 0.1524)
				(type default)
			)
			(layer "F.SilkS")
		)
		(fp_line
			(start 0.7874 -0.4064)
			(end 0.7874 0.4064)
			(stroke
				(width 0.1524)
				(type default)
			)
			(layer "F.SilkS")
		)
		(fp_line
			(start -0.7874 0.4064)
			(end -0.7874 -0.4064)
			(stroke
				(width 0.1524)
				(type default)
			)
			(layer "F.SilkS")
		)
		(fp_line
			(start -0.7874 -0.4064)
			(end 0.7874 -0.4064)
			(stroke
				(width 0.1524)
				(type default)
			)
			(layer "F.SilkS")
		)
		(fp_line
			(start 0.67945 0.3048)
			(end 0.120396 0.3048)
			(stroke
				(width 0.1)
				(type default)
			)
			(layer "F.Fab")
		)
		(fp_line
			(start 0.67945 -0.3048)
			(end 0.67945 0.3048)
			(stroke
				(width 0.1)
				(type default)
			)
			(layer "F.Fab")
		)
		(fp_line
			(start 0.12065 -0.2794)
			(end 0.12065 -0.3048)
			(stroke
				(width 0.1)
				(type default)
			)
			(layer "F.Fab")
		)
		(fp_line
			(start 0.12065 -0.3048)
			(end 0.67945 -0.3048)
			(stroke
				(width 0.1)
				(type default)
			)
			(layer "F.Fab")
		)
		(fp_line
			(start 0.120396 0.3048)
			(end 0.120396 0.2794)
			(stroke
				(width 0.1)
				(type default)
			)
			(layer "F.Fab")
		)
		(fp_line
			(start 0.120396 0.2794)
			(end -0.12065 0.2794)
			(stroke
				(width 0.1)
				(type default)
			)
			(layer "F.Fab")
		)
		(fp_line
			(start -0.12065 0.3048)
			(end -0.67945 0.3048)
			(stroke
				(width 0.1)
				(type default)
			)
			(layer "F.Fab")
		)
		(fp_line
			(start -0.12065 0.2794)
			(end -0.12065 0.3048)
			(stroke
				(width 0.1)
				(type default)
			)
			(layer "F.Fab")
		)
		(fp_line
			(start -0.12065 -0.2794)
			(end 0.12065 -0.2794)
			(stroke
				(width 0.1)
				(type default)
			)
			(layer "F.Fab")
		)
		(fp_line
			(start -0.12065 -0.305054)
			(end -0.12065 -0.2794)
			(stroke
				(width 0.1)
				(type default)
			)
			(layer "F.Fab")
		)
		(fp_line
			(start -0.67945 0.3048)
			(end -0.67945 -0.305054)
			(stroke
				(width 0.1)
				(type default)
			)
			(layer "F.Fab")
		)
		(fp_line
			(start -0.67945 -0.305054)
			(end -0.12065 -0.305054)
			(stroke
				(width 0.1)
				(type default)
			)
			(layer "F.Fab")
		)
		(pad "1" smd circle
			(at -0.40005 0 180)
			(size 0 0)
			(layers "F.Cu" "F.Mask" "F.Paste")
			(net "PEX1_PCA9555_INT_R_N")
		)
		(pad "2" smd circle
			(at 0.40005 0 180)
			(size 0 0)
			(layers "F.Cu" "F.Mask" "F.Paste")
			(net "PEX1_PCA9555_INT_N")
		)
	)
	(footprint ""
		(layer "F.Cu")
		(at 219.202 -202.184)
		(property "Reference" "R1516"
			(at 0 0 0)
			(layer "F.SilkS")
			(hide yes)
			(effects
				(font
					(size 1.27 1.27)
				)
			)
		)
		(property "Value" ""
			(at 0 0 0)
			(layer "F.Fab")
			(effects
				(font
					(size 1.27 1.27)
				)
			)
		)
		(duplicate_pad_numbers_are_jumpers no)
		(fp_line
			(start -0.7874 -0.4064)
			(end 0.7874 -0.4064)
			(stroke
				(width 0.1524)
				(type default)
			)
			(layer "F.SilkS")
		)
		(fp_line
			(start -0.7874 0.4064)
			(end -0.7874 -0.4064)
			(stroke
				(width 0.1524)
				(type default)
			)
			(layer "F.SilkS")
		)
		(fp_line
			(start 0.7874 -0.4064)
			(end 0.7874 0.4064)
			(stroke
				(width 0.1524)
				(type default)
			)
			(layer "F.SilkS")
		)
		(fp_line
			(start 0.7874 0.4064)
			(end -0.7874 0.4064)
			(stroke
				(width 0.1524)
				(type default)
			)
			(layer "F.SilkS")
		)
		(fp_line
			(start -0.67945 -0.305054)
			(end -0.12065 -0.305054)
			(stroke
				(width 0.1)
				(type default)
			)
			(layer "F.Fab")
		)
		(fp_line
			(start -0.67945 0.3048)
			(end -0.67945 -0.305054)
			(stroke
				(width 0.1)
				(type default)
			)
			(layer "F.Fab")
		)
		(fp_line
			(start -0.12065 -0.305054)
			(end -0.12065 -0.2794)
			(stroke
				(width 0.1)
				(type default)
			)
			(layer "F.Fab")
		)
		(fp_line
			(start -0.12065 -0.2794)
			(end 0.12065 -0.2794)
			(stroke
				(width 0.1)
				(type default)
			)
			(layer "F.Fab")
		)
		(fp_line
			(start -0.12065 0.2794)
			(end -0.12065 0.3048)
			(stroke
				(width 0.1)
				(type default)
			)
			(layer "F.Fab")
		)
		(fp_line
			(start -0.12065 0.3048)
			(end -0.67945 0.3048)
			(stroke
				(width 0.1)
				(type default)
			)
			(layer "F.Fab")
		)
		(fp_line
			(start 0.120396 0.2794)
			(end -0.12065 0.2794)
			(stroke
				(width 0.1)
				(type default)
			)
			(layer "F.Fab")
		)
		(fp_line
			(start 0.120396 0.3048)
			(end 0.120396 0.2794)
			(stroke
				(width 0.1)
				(type default)
			)
			(layer "F.Fab")
		)
		(fp_line
			(start 0.12065 -0.3048)
			(end 0.67945 -0.3048)
			(stroke
				(width 0.1)
				(type default)
			)
			(layer "F.Fab")
		)
		(fp_line
			(start 0.12065 -0.2794)
			(end 0.12065 -0.3048)
			(stroke
				(width 0.1)
				(type default)
			)
			(layer "F.Fab")
		)
		(fp_line
			(start 0.67945 -0.3048)
			(end 0.67945 0.3048)
			(stroke
				(width 0.1)
				(type default)
			)
			(layer "F.Fab")
		)
		(fp_line
			(start 0.67945 0.3048)
			(end 0.120396 0.3048)
			(stroke
				(width 0.1)
				(type default)
			)
			(layer "F.Fab")
		)
		(pad "1" smd circle
			(at -0.40005 0)
			(size 0 0)
			(layers "F.Cu" "F.Mask" "F.Paste")
			(net "SMB_NIC5_LS_R_SCL")
		)
		(pad "2" smd circle
			(at 0.40005 0)
			(size 0 0)
			(layers "F.Cu" "F.Mask" "F.Paste")
			(net "P3V3_NIC5")
		)
	)
	(footprint ""
		(layer "F.Cu")
		(at 248.126504 -121.408952 180)
		(property "Reference" "PC449"
			(at 0 0 180)
			(layer "F.SilkS")
			(hide yes)
			(effects
				(font
					(size 1.27 1.27)
				)
			)
		)
		(property "Value" ""
			(at 0 0 180)
			(layer "F.Fab")
			(effects
				(font
					(size 1.27 1.27)
				)
			)
		)
		(duplicate_pad_numbers_are_jumpers no)
		(fp_line
			(start 1.524 0.762)
			(end -1.524 0.762)
			(stroke
				(width 0.1524)
				(type default)
			)
			(layer "F.SilkS")
		)
		(fp_line
			(start 1.524 -0.762)
			(end 1.524 0.762)
			(stroke
				(width 0.1524)
				(type default)
			)
			(layer "F.SilkS")
		)
		(fp_line
			(start -1.524 0.762)
			(end -1.524 -0.762)
			(stroke
				(width 0.1524)
				(type default)
			)
			(layer "F.SilkS")
		)
		(fp_line
			(start -1.524 -0.762)
			(end 1.524 -0.762)
			(stroke
				(width 0.1524)
				(type default)
			)
			(layer "F.SilkS")
		)
		(fp_line
			(start 1.1049 0.724916)
			(end 1.1049 -0.724916)
			(stroke
				(width 0.1)
				(type default)
			)
			(layer "F.Fab")
		)
		(fp_line
			(start 1.1049 -0.724916)
			(end -1.1049 -0.724916)
			(stroke
				(width 0.1)
				(type default)
			)
			(layer "F.Fab")
		)
		(fp_line
			(start -1.1049 0.724916)
			(end 1.1049 0.724916)
			(stroke
				(width 0.1)
				(type default)
			)
			(layer "F.Fab")
		)
		(fp_line
			(start -1.1049 -0.724916)
			(end -1.1049 0.724916)
			(stroke
				(width 0.1)
				(type default)
			)
			(layer "F.Fab")
		)
		(pad "1" smd rect
			(at -0.889 0)
			(size 1.016 1.27)
			(layers "F.Cu" "F.Mask" "F.Paste")
			(net "GND")
		)
		(pad "2" smd rect
			(at 0.889 0)
			(size 1.016 1.27)
			(layers "F.Cu" "F.Mask" "F.Paste")
			(net "P3V3_AUX")
		)
	)
	(footprint ""
		(layer "F.Cu")
		(at 11.956796 -394.137134 -90)
		(property "Reference" "R6743"
			(at 0 0 270)
			(layer "F.SilkS")
			(hide yes)
			(effects
				(font
					(size 1.27 1.27)
				)
			)
		)
		(property "Value" ""
			(at 0 0 270)
			(layer "F.Fab")
			(effects
				(font
					(size 1.27 1.27)
				)
			)
		)
		(duplicate_pad_numbers_are_jumpers no)
		(fp_line
			(start -0.7874 0.4064)
			(end -0.7874 -0.4064)
			(stroke
				(width 0.1524)
				(type default)
			)
			(layer "F.SilkS")
		)
		(fp_line
			(start 0.7874 0.4064)
			(end -0.7874 0.4064)
			(stroke
				(width 0.1524)
				(type default)
			)
			(layer "F.SilkS")
		)
		(fp_line
			(start -0.7874 -0.4064)
			(end 0.7874 -0.4064)
			(stroke
				(width 0.1524)
				(type default)
			)
			(layer "F.SilkS")
		)
		(fp_line
			(start 0.7874 -0.4064)
			(end 0.7874 0.4064)
			(stroke
				(width 0.1524)
				(type default)
			)
			(layer "F.SilkS")
		)
		(fp_line
			(start -0.67945 0.3048)
			(end -0.67945 -0.305054)
			(stroke
				(width 0.1)
				(type default)
			)
			(layer "F.Fab")
		)
		(fp_line
			(start -0.12065 0.3048)
			(end -0.67945 0.3048)
			(stroke
				(width 0.1)
				(type default)
			)
			(layer "F.Fab")
		)
		(fp_line
			(start 0.120396 0.3048)
			(end 0.120396 0.2794)
			(stroke
				(width 0.1)
				(type default)
			)
			(layer "F.Fab")
		)
		(fp_line
			(start 0.67945 0.3048)
			(end 0.120396 0.3048)
			(stroke
				(width 0.1)
				(type default)
			)
			(layer "F.Fab")
		)
		(fp_line
			(start -0.12065 0.2794)
			(end -0.12065 0.3048)
			(stroke
				(width 0.1)
				(type default)
			)
			(layer "F.Fab")
		)
		(fp_line
			(start 0.120396 0.2794)
			(end -0.12065 0.2794)
			(stroke
				(width 0.1)
				(type default)
			)
			(layer "F.Fab")
		)
		(fp_line
			(start -0.12065 -0.2794)
			(end 0.12065 -0.2794)
			(stroke
				(width 0.1)
				(type default)
			)
			(layer "F.Fab")
		)
		(fp_line
			(start 0.12065 -0.2794)
			(end 0.12065 -0.3048)
			(stroke
				(width 0.1)
				(type default)
			)
			(layer "F.Fab")
		)
		(fp_line
			(start 0.12065 -0.3048)
			(end 0.67945 -0.3048)
			(stroke
				(width 0.1)
				(type default)
			)
			(layer "F.Fab")
		)
		(fp_line
			(start 0.67945 -0.3048)
			(end 0.67945 0.3048)
			(stroke
				(width 0.1)
				(type default)
			)
			(layer "F.Fab")
		)
		(fp_line
			(start -0.67945 -0.305054)
			(end -0.12065 -0.305054)
			(stroke
				(width 0.1)
				(type default)
			)
			(layer "F.Fab")
		)
		(fp_line
			(start -0.12065 -0.305054)
			(end -0.12065 -0.2794)
			(stroke
				(width 0.1)
				(type default)
			)
			(layer "F.Fab")
		)
		(pad "1" smd circle
			(at -0.40005 0 270)
			(size 0 0)
			(layers "F.Cu" "F.Mask" "F.Paste")
			(net "P3V3_USB_8042")
		)
		(pad "2" smd circle
			(at 0.40005 0 270)
			(size 0 0)
			(layers "F.Cu" "F.Mask" "F.Paste")
			(net "BIC_USB_8042_HUB_OVCUR4")
		)
	)
)
